# S9S_MB_2U (Grand Teton) — schematic netlist excerpt (pin names and nets, part order shuffled) for the footprints in the layout excerpt that follows; sources: Cadence DE-HDL packaged netlist, KiCad conversion of 03242023_DA0F0TMBIJ0_F0T_Motherboard_J_brd_V01_OCP.brd

J22  SCONN288_ADR50017P087CC  SCONN288_ADR50017-P087CC IO  pkg DDR288S_1-1VXB  page 103
  VIN_BULK0  = P12V_S3_AUX_CPU1_NVDIMM
  RFU0  = TP_CHC_CPU1_DIMM2_FRU_0
  VIN_MGMT  = P3V3_AUX
  HSCL  = I3C_SPD_DDRABCD_CPU1_LVC1_SCL_5
  HSDA  = I3C_SPD_DDRABCD_CPU1_LVC1_SDA
  VSS0  = GND
  DQ0_A  = M_C_CPU1_SA_DQ<0>
  VSS1  = GND
  DQ1_A  = M_C_CPU1_SA_DQ<1>
  VSS2  = GND
  DQS0_A_T  = M_C_CPU1_SA_DQS_DP<0>
  DQS0_A_C  = M_C_CPU1_SA_DQS_DN<0>
  VSS3  = GND
  DQ4_A  = M_C_CPU1_SA_DQ<4>
  VSS4  = GND
  DQ5_A  = M_C_CPU1_SA_DQ<5>
  VSS5  = GND
  DQ8_A  = M_C_CPU1_SA_DQ<8>
  VSS6  = GND
  DQ9_A  = M_C_CPU1_SA_DQ<9>
  VSS7  = GND
  DQS1_A_T  = M_C_CPU1_SA_DQS_DP<1>
  DQS1_A_C  = M_C_CPU1_SA_DQS_DN<1>
  VSS8  = GND
  DQ12_A  = M_C_CPU1_SA_DQ<12>
  VSS9  = GND
  DQ13_A  = M_C_CPU1_SA_DQ<13>
  VSS10  = GND
  DQ16_A  = M_C_CPU1_SA_DQ<16>
  VSS11  = GND
  DQ17_A  = M_C_CPU1_SA_DQ<17>
  VSS12  = GND
  DQS2_A_T  = M_C_CPU1_SA_DQS_DP<2>
  DQS2_A_C  = M_C_CPU1_SA_DQS_DN<2>
  VSS13  = GND
  DQ20_A  = M_C_CPU1_SA_DQ<20>
  VSS14  = GND
  DQ21_A  = M_C_CPU1_SA_DQ<21>
  VSS15  = GND
  DQ24_A  = M_C_CPU1_SA_DQ<24>
  VSS16  = GND
  DQ25_A  = M_C_CPU1_SA_DQ<25>
  VSS17  = GND
  DQS3_A_T  = M_C_CPU1_SA_DQS_DP<3>
  DQS3_A_C  = M_C_CPU1_SA_DQS_DN<3>
  VSS18  = GND
  DQ28_A  = M_C_CPU1_SA_DQ<28>
  VSS19  = GND
  DQ29_A  = M_C_CPU1_SA_DQ<29>
  VSS20  = GND
  CB0_A  = M_C_CPU1_SA_CB<0>
  VSS21  = GND
  CB1_A  = M_C_CPU1_SA_CB<1>
  VSS22  = GND
  DQS4_A_T  = M_C_CPU1_SA_DQS_DP<4>
  DQS4_A_C  = M_C_CPU1_SA_DQS_DN<4>
  VSS23  = GND
  CB4_A  = M_C_CPU1_SA_CB<4>
  VSS24  = GND
  CB5_A  = M_C_CPU1_SA_CB<5>
  VSS25  = GND
  ALERT_N  = M_C_CPU1_ALERT_N
  VSS26  = GND
  CS0_A_N  = M_C_CPU1_SA_CS_N<2>
  VSS27  = GND
  CA0_A  = M_C_CPU1_SA_CA<0>
  VSS28  = GND
  CA2_A  = M_C_CPU1_SA_CA<2>
  VSS29  = GND
  CA4_A  = M_C_CPU1_SA_CA<4>
  VSS30  = GND
  CA6_A  = M_C_CPU1_SA_CA<6>
  VSS31  = GND
  PAR_A  = M_C_CPU1_SA_PAR
  VSS32  = GND
  CA0_B  = M_C_CPU1_SB_CA<0>
  VSS33  = GND
  CA2_B  = M_C_CPU1_SB_CA<2>
  VSS34  = GND
  CA4_B  = M_C_CPU1_SB_CA<4>
  VSS35  = GND
  CA6_B  = M_C_CPU1_SB_CA<6>
  VSS36  = GND
  CS0_B_N  = M_C_CPU1_SB_CS_N<2>
  VSS37  = GND
  \lbd||rsp_a_n\  = M_C_CPU1_SA_RSP<1>
  \lbs||rsp_b_n\  = M_C_CPU1_SB_RSP<1>
  VSS38  = GND
  CB4_B  = M_C_CPU1_SB_CB<4>
  VSS39  = GND
  CB5_B  = M_C_CPU1_SB_CB<5>
  VSS40  = GND
  \dqs9_b_t||tdqs9_b_t||dbi4_b_n\  = M_C_CPU1_SB_DQS_DP<9>
  \dqs9_b_c||tdqs9_b_c\  = M_C_CPU1_SB_DQS_DN<9>
  VSS41  = GND
  CB0_B  = M_C_CPU1_SB_CB<0>
  VSS42  = GND
  CB1_B  = M_C_CPU1_SB_CB<1>
  VSS43  = GND
  DQ0_B  = M_C_CPU1_SB_DQ<0>
  VSS44  = GND
  DQ1_B  = M_C_CPU1_SB_DQ<1>
  VSS45  = GND
  DQS0_B_T  = M_C_CPU1_SB_DQS_DP<0>
  DQS0_B_C  = M_C_CPU1_SB_DQS_DN<0>
  VSS46  = GND
  DQ4_B  = M_C_CPU1_SB_DQ<4>
  VSS47  = GND
  DQ5_B  = M_C_CPU1_SB_DQ<5>
  VSS48  = GND
  DQ8_B  = M_C_CPU1_SB_DQ<8>
  VSS49  = GND
  DQ9_B  = M_C_CPU1_SB_DQ<9>
  VSS50  = GND
  DQS1_B_T  = M_C_CPU1_SB_DQS_DP<1>
  DQS1_B_C  = M_C_CPU1_SB_DQS_DN<1>
  VSS51  = GND
  DQ12_B  = M_C_CPU1_SB_DQ<12>
  VSS52  = GND
  DQ13_B  = M_C_CPU1_SB_DQ<13>
  VSS53  = GND
  DQ16_B  = M_C_CPU1_SB_DQ<16>
  VSS54  = GND
  DQ17_B  = M_C_CPU1_SB_DQ<17>
  VSS55  = GND
  DQS2_B_T  = M_C_CPU1_SB_DQS_DP<2>
  DQS2_B_C  = M_C_CPU1_SB_DQS_DN<2>
  VSS56  = GND
  DQ20_B  = M_C_CPU1_SB_DQ<20>
  VSS57  = GND
  DQ21_B  = M_C_CPU1_SB_DQ<21>
  VSS58  = GND
  DQ24_B  = M_C_CPU1_SB_DQ<24>
  VSS59  = GND
  DQ25_B  = M_C_CPU1_SB_DQ<25>
  VSS60  = GND
  DQS3_B_T  = M_C_CPU1_SB_DQS_DP<3>
  DQS3_B_C  = M_C_CPU1_SB_DQS_DN<3>
  VSS61  = GND
  DQ28_B  = M_C_CPU1_SB_DQ<28>
  VSS62  = GND
  DQ29_B  = M_C_CPU1_SB_DQ<29>
  VSS63  = GND
  RFU1  = TP_CHC_CPU1_DIMM2_FRU_1
  VIN_BULK1  = P12V_S3_AUX_CPU1_NVDIMM
  VIN_BULK2  = P12V_S3_AUX_CPU1_NVDIMM
  \pwr_good||fail_n\  = PWRGD_CHC_CPU1_DIMM2
  HSA  = PD_CHC_CPU1_DIMM2_SAA
  RFU2  = TP_CHC_CPU1_DIMM2_FRU_2
  RFU3  = TP_CHC_CPU1_DIMM2_FRU_3
  VSS64  = GND
  DQ2_A  = M_C_CPU1_SA_DQ<2>
  VSS65  = GND
  DQ3_A  = M_C_CPU1_SA_DQ<3>
  VSS66  = GND
  \dqs5_a_c||tdqs5_a_c||dqs5_a_t||tdqs5_a_t\  = M_C_CPU1_SA_DQS_DN<5>
  \dqs5_a_t||tdqs5_a_t\  = M_C_CPU1_SA_DQS_DP<5>
  VSS67  = GND
  DQ6_A  = M_C_CPU1_SA_DQ<6>
  VSS68  = GND
  DQ7_A  = M_C_CPU1_SA_DQ<7>
  VSS69  = GND
  DQ10_A  = M_C_CPU1_SA_DQ<10>
  VSS70  = GND
  DQ11_A  = M_C_CPU1_SA_DQ<11>
  VSS71  = GND
  \dqs6_a_c||tdqs6_a_c||dqs6_a_t||tdqs6_a_t\  = M_C_CPU1_SA_DQS_DN<6>
  \dqs6_a_t||tdqs6_a_t\  = M_C_CPU1_SA_DQS_DP<6>
  VSS72  = GND
  DQ14_A  = M_C_CPU1_SA_DQ<14>
  VSS73  = GND
  DQ15_A  = M_C_CPU1_SA_DQ<15>
  VSS74  = GND
  DQ18_A  = M_C_CPU1_SA_DQ<18>
  VSS75  = GND
  DQ19_A  = M_C_CPU1_SA_DQ<19>
  VSS76  = GND
  \dqs7_a_c||tdqs7_a_c\  = M_C_CPU1_SA_DQS_DN<7>
  \dqs7_a_t||tdqs7_a_t\  = M_C_CPU1_SA_DQS_DP<7>
  VSS77  = GND
  DQ22_A  = M_C_CPU1_SA_DQ<22>
  VSS78  = GND
  DQ23_A  = M_C_CPU1_SA_DQ<23>
  VSS79  = GND
  DQ26_A  = M_C_CPU1_SA_DQ<26>
  VSS80  = GND
  DQ27_A  = M_C_CPU1_SA_DQ<27>
  VSS81  = GND
  \dqs8_a_c||tdqs8_a_c\  = M_C_CPU1_SA_DQS_DN<8>
  \dqs8_a_t||tdqs8_a_t\  = M_C_CPU1_SA_DQS_DP<8>
  VSS82  = GND
  DQ30_A  = M_C_CPU1_SA_DQ<30>
  VSS83  = GND
  DQ31_A  = M_C_CPU1_SA_DQ<31>
  VSS84  = GND
  CB2_A  = M_C_CPU1_SA_CB<2>
  VSS85  = GND
  CB3_A  = M_C_CPU1_SA_CB<3>
  VSS86  = GND
  \dqs9_a_c||tdqs9_a_c\  = M_C_CPU1_SA_DQS_DN<9>
  \dqs9_a_t||tdqs9_a_t\  = M_C_CPU1_SA_DQS_DP<9>
  VSS87  = GND
  CB6_A  = M_C_CPU1_SA_CB<6>
  VSS88  = GND
  CB7_A  = M_C_CPU1_SA_CB<7>
  VSS89  = GND
  RESET_N  = RST_M_CD_CPU1_FPGA_N
  VSS90  = GND
  CS1_A_N  = M_C_CPU1_SA_CS_N<3>
  VSS91  = GND
  CA1_A  = M_C_CPU1_SA_CA<1>
  VSS92  = GND
  CA3_A  = M_C_CPU1_SA_CA<3>
  VSS93  = GND
  CA5_A  = M_C_CPU1_SA_CA<5>
  VSS94  = GND
  CK_T  = M_C_CPU1_CLK_DP<1>
  CK_C  = M_C_CPU1_CLK_DN<1>
  VSS95  = GND
  RFU4  = TP_CHC_CPU1_DIMM2_FRU_4
  CA1_B  = M_C_CPU1_SB_CA<1>
  VSS96  = GND
  CA3_B  = M_C_CPU1_SB_CA<3>
  VSS97  = GND
  CA5_B  = M_C_CPU1_SB_CA<5>
  VSS98  = GND
  PAR_B  = M_C_CPU1_SB_PAR
  VSS99  = GND
  CS1_B_N  = M_C_CPU1_SB_CS_N<3>
  VSS100  = GND
  RFU5  = TP_CHC_CPU1_DIMM2_FRU_5
  RFU6  = TP_CHC_CPU1_DIMM2_FRU_6
  VSS101  = GND
  CB6_B  = M_C_CPU1_SB_CB<6>
  VSS102  = GND
  CB7_B  = M_C_CPU1_SB_CB<7>
  VSS103  = GND
  DQS4_B_C  = M_C_CPU1_SB_DQS_DN<4>
  DQS4_B_T  = M_C_CPU1_SB_DQS_DP<4>
  VSS104  = GND
  CB2_B  = M_C_CPU1_SB_CB<2>
  VSS105  = GND
  CB3_B  = M_C_CPU1_SB_CB<3>
  VSS106  = GND
  DQ2_B  = M_C_CPU1_SB_DQ<2>
  VSS107  = GND
  DQ3_B  = M_C_CPU1_SB_DQ<3>
  VSS108  = GND
  \dqs5_b_c||tdqs5_b_c\  = M_C_CPU1_SB_DQS_DN<5>
  \dqs5_b_t||tdqs5_b_t\  = M_C_CPU1_SB_DQS_DP<5>
  VSS109  = GND
  DQ6_B  = M_C_CPU1_SB_DQ<6>
  VSS110  = GND
  DQ7_B  = M_C_CPU1_SB_DQ<7>
  VSS111  = GND
  DQ10_B  = M_C_CPU1_SB_DQ<10>
  VSS112  = GND
  DQ11_B  = M_C_CPU1_SB_DQ<11>
  VSS113  = GND
  \dqs6_b_c||tdqs6_b_c\  = M_C_CPU1_SB_DQS_DN<6>
  \dqs6_b_t||tdqs6_b_t\  = M_C_CPU1_SB_DQS_DP<6>
  VSS114  = GND
  DQ14_B  = M_C_CPU1_SB_DQ<14>
  VSS115  = GND
  DQ15_B  = M_C_CPU1_SB_DQ<15>
  VSS116  = GND
  DQ18_B  = M_C_CPU1_SB_DQ<18>
  VSS117  = GND
  DQ19_B  = M_C_CPU1_SB_DQ<19>
  VSS118  = GND
  \dqs7_b_c||tdqs7_b_c\  = M_C_CPU1_SB_DQS_DN<7>
  \dqs7_b_t||tdqs7_b_t\  = M_C_CPU1_SB_DQS_DP<7>
  VSS119  = GND
  DQ22_B  = M_C_CPU1_SB_DQ<22>
  VSS120  = GND
  DQ23_B  = M_C_CPU1_SB_DQ<23>
  VSS121  = GND
  DQ26_B  = M_C_CPU1_SB_DQ<26>
  VSS122  = GND
  DQ27_B  = M_C_CPU1_SB_DQ<27>
  VSS123  = GND
  \dqs8_b_c||tdqs8_b_c\  = M_C_CPU1_SB_DQS_DN<8>
  \dqs8_b_t||tdqs8_b_t\  = M_C_CPU1_SB_DQS_DP<8>
  VSS124  = GND
  DQ30_B  = M_C_CPU1_SB_DQ<30>
  VSS125  = GND
  DQ31_B  = M_C_CPU1_SB_DQ<31>
  VSS126  = GND
  G1  = GND
  G2  = GND
  G3  = GND

(kicad_pcb
	(version 20260206)
	(generator "pcbnew")
	(generator_version "10.0")
	(general
		(thickness 1.6)
		(legacy_teardrops no)
	)
	(paper "A4")
	(title_block
		(title "03242023_DA0F0TMBIJ0_F0T_Motherboard_J_brd_V01_OCP.brd")
		(comment 1 "Grand Teton / footprint 501 of 6105 (J22), pads 229-274 of 291")
	)
	(layers
		(0 "F.Cu" signal "TOP")
		(4 "In1.Cu" signal "GND")
		(6 "In2.Cu" signal "IN1")
		(8 "In3.Cu" signal "GND1")
		(10 "In4.Cu" signal "IN2")
		(12 "In5.Cu" signal "GND2")
		(14 "In6.Cu" signal "IN3")
		(16 "In7.Cu" signal "GND3")
		(18 "In8.Cu" signal "VCC")
		(20 "In9.Cu" signal "VCC1")
		(22 "In10.Cu" signal "GND4")
		(24 "In11.Cu" signal "IN4")
		(26 "In12.Cu" signal "GND5")
		(28 "In13.Cu" signal "IN5")
		(30 "In14.Cu" signal "GND6")
		(32 "In15.Cu" signal "IN6")
		(34 "In16.Cu" signal "GND7")
		(2 "B.Cu" signal "BOTTOM")
		(9 "F.Adhes" user "F.Adhesive")
		(11 "B.Adhes" user "B.Adhesive")
		(13 "F.Paste" user "Package Geometry/Pastemask Top")
		(15 "B.Paste" user "Package Geometry/Pastemask Bottom")
		(5 "F.SilkS" user "Ref Des/Silkscreen Top")
		(7 "B.SilkS" user "Ref Des/Silkscreen Bottom")
		(1 "F.Mask" user "Board Geometry/Soldermask Top")
		(3 "B.Mask" user "Board Geometry/Soldermask Bottom")
		(17 "Dwgs.User" user "User.Drawings")
		(19 "Cmts.User" user "User.Comments")
		(21 "Eco1.User" user "User.Eco1")
		(23 "Eco2.User" user "User.Eco2")
		(25 "Edge.Cuts" user "Board Geometry/Outline")
		(27 "Margin" user)
		(31 "F.CrtYd" user "Package Geometry/Place Bound Top")
		(29 "B.CrtYd" user "Package Geometry/Place Bound Bottom")
		(35 "F.Fab" user "Ref Des/Assembly Top")
		(33 "B.Fab" user "Ref Des/Assembly Bottom")
	)
	(footprint ""
		(layer "F.Cu")
		(at 32.82188 -258.091686)
		(property "Reference" "J22"
			(at -1.420622 -81.912714 0)
			(unlocked yes)
			(layer "F.SilkS")
			(effects
				(font
					(size 0.7874 0.5842)
					(thickness 0.1524)
				)
				(justify left)
			)
		)
		(property "Value" ""
			(at 0 0 0)
			(layer "F.Fab")
			(effects
				(font
					(size 1.27 1.27)
				)
			)
		)
		(duplicate_pad_numbers_are_jumpers no)
		(pad "229" smd rect
			(at 2.050034 13.17498 270)
			(size 0.519938 1.4986)
			(layers "F.Cu" "F.Mask" "F.Paste")
			(net "M_C_CPU1_SB_CS_N<3>")
		)
		(pad "230" smd rect
			(at 2.050034 14.025118 270)
			(size 0.519938 1.4986)
			(layers "F.Cu" "F.Mask" "F.Paste")
			(net "GND")
		)
		(pad "231" smd rect
			(at 2.050034 14.875002 270)
			(size 0.519938 1.4986)
			(layers "F.Cu" "F.Mask" "F.Paste")
			(net "TP_CHC_CPU1_DIMM2_FRU_5")
		)
		(pad "232" smd rect
			(at 2.050034 15.724886 270)
			(size 0.519938 1.4986)
			(layers "F.Cu" "F.Mask" "F.Paste")
			(net "TP_CHC_CPU1_DIMM2_FRU_6")
		)
		(pad "233" smd rect
			(at 2.050034 16.575024 270)
			(size 0.519938 1.4986)
			(layers "F.Cu" "F.Mask" "F.Paste")
			(net "GND")
		)
		(pad "234" smd rect
			(at 2.050034 17.424908 270)
			(size 0.519938 1.4986)
			(layers "F.Cu" "F.Mask" "F.Paste")
			(net "M_C_CPU1_SB_CB<6>")
		)
		(pad "235" smd rect
			(at 2.050034 18.275046 270)
			(size 0.519938 1.4986)
			(layers "F.Cu" "F.Mask" "F.Paste")
			(net "GND")
		)
		(pad "236" smd rect
			(at 2.050034 19.12493 270)
			(size 0.519938 1.4986)
			(layers "F.Cu" "F.Mask" "F.Paste")
			(net "M_C_CPU1_SB_CB<7>")
		)
		(pad "237" smd rect
			(at 2.050034 19.975068 270)
			(size 0.519938 1.4986)
			(layers "F.Cu" "F.Mask" "F.Paste")
			(net "GND")
		)
		(pad "238" smd rect
			(at 2.050034 20.824952 270)
			(size 0.519938 1.4986)
			(layers "F.Cu" "F.Mask" "F.Paste")
			(net "M_C_CPU1_SB_DQS_DN<4>")
		)
		(pad "239" smd rect
			(at 2.050034 21.67509 270)
			(size 0.519938 1.4986)
			(layers "F.Cu" "F.Mask" "F.Paste")
			(net "M_C_CPU1_SB_DQS_DP<4>")
		)
		(pad "240" smd rect
			(at 2.050034 22.524974 270)
			(size 0.519938 1.4986)
			(layers "F.Cu" "F.Mask" "F.Paste")
			(net "GND")
		)
		(pad "241" smd rect
			(at 2.050034 23.375112 270)
			(size 0.519938 1.4986)
			(layers "F.Cu" "F.Mask" "F.Paste")
			(net "M_C_CPU1_SB_CB<2>")
		)
		(pad "242" smd rect
			(at 2.050034 24.224996 270)
			(size 0.519938 1.4986)
			(layers "F.Cu" "F.Mask" "F.Paste")
			(net "GND")
		)
		(pad "243" smd rect
			(at 2.050034 25.07488 270)
			(size 0.519938 1.4986)
			(layers "F.Cu" "F.Mask" "F.Paste")
			(net "M_C_CPU1_SB_CB<3>")
		)
		(pad "244" smd rect
			(at 2.050034 25.925018 270)
			(size 0.519938 1.4986)
			(layers "F.Cu" "F.Mask" "F.Paste")
			(net "GND")
		)
		(pad "245" smd rect
			(at 2.050034 26.774902 270)
			(size 0.519938 1.4986)
			(layers "F.Cu" "F.Mask" "F.Paste")
			(net "M_C_CPU1_SB_DQ<2>")
		)
		(pad "246" smd rect
			(at 2.050034 27.62504 270)
			(size 0.519938 1.4986)
			(layers "F.Cu" "F.Mask" "F.Paste")
			(net "GND")
		)
		(pad "247" smd rect
			(at 2.050034 28.474924 270)
			(size 0.519938 1.4986)
			(layers "F.Cu" "F.Mask" "F.Paste")
			(net "M_C_CPU1_SB_DQ<3>")
		)
		(pad "248" smd rect
			(at 2.050034 29.325062 270)
			(size 0.519938 1.4986)
			(layers "F.Cu" "F.Mask" "F.Paste")
			(net "GND")
		)
		(pad "249" smd rect
			(at 2.050034 30.174946 270)
			(size 0.519938 1.4986)
			(layers "F.Cu" "F.Mask" "F.Paste")
			(net "M_C_CPU1_SB_DQS_DN<5>")
		)
		(pad "250" smd rect
			(at 2.050034 31.025084 270)
			(size 0.519938 1.4986)
			(layers "F.Cu" "F.Mask" "F.Paste")
			(net "M_C_CPU1_SB_DQS_DP<5>")
		)
		(pad "251" smd rect
			(at 2.050034 31.874968 270)
			(size 0.519938 1.4986)
			(layers "F.Cu" "F.Mask" "F.Paste")
			(net "GND")
		)
		(pad "252" smd rect
			(at 2.050034 32.725106 270)
			(size 0.519938 1.4986)
			(layers "F.Cu" "F.Mask" "F.Paste")
			(net "M_C_CPU1_SB_DQ<6>")
		)
		(pad "253" smd rect
			(at 2.050034 33.57499 270)
			(size 0.519938 1.4986)
			(layers "F.Cu" "F.Mask" "F.Paste")
			(net "GND")
		)
		(pad "254" smd rect
			(at 2.050034 34.425128 270)
			(size 0.519938 1.4986)
			(layers "F.Cu" "F.Mask" "F.Paste")
			(net "M_C_CPU1_SB_DQ<7>")
		)
		(pad "255" smd rect
			(at 2.050034 35.275012 270)
			(size 0.519938 1.4986)
			(layers "F.Cu" "F.Mask" "F.Paste")
			(net "GND")
		)
		(pad "256" smd rect
			(at 2.050034 36.124896 270)
			(size 0.519938 1.4986)
			(layers "F.Cu" "F.Mask" "F.Paste")
			(net "M_C_CPU1_SB_DQ<10>")
		)
		(pad "257" smd rect
			(at 2.050034 36.975034 270)
			(size 0.519938 1.4986)
			(layers "F.Cu" "F.Mask" "F.Paste")
			(net "GND")
		)
		(pad "258" smd rect
			(at 2.050034 37.824918 270)
			(size 0.519938 1.4986)
			(layers "F.Cu" "F.Mask" "F.Paste")
			(net "M_C_CPU1_SB_DQ<11>")
		)
		(pad "259" smd rect
			(at 2.050034 38.675056 270)
			(size 0.519938 1.4986)
			(layers "F.Cu" "F.Mask" "F.Paste")
			(net "GND")
		)
		(pad "260" smd rect
			(at 2.050034 39.52494 270)
			(size 0.519938 1.4986)
			(layers "F.Cu" "F.Mask" "F.Paste")
			(net "M_C_CPU1_SB_DQS_DN<6>")
		)
		(pad "261" smd rect
			(at 2.050034 40.375078 270)
			(size 0.519938 1.4986)
			(layers "F.Cu" "F.Mask" "F.Paste")
			(net "M_C_CPU1_SB_DQS_DP<6>")
		)
		(pad "262" smd rect
			(at 2.050034 41.224962 270)
			(size 0.519938 1.4986)
			(layers "F.Cu" "F.Mask" "F.Paste")
			(net "GND")
		)
		(pad "263" smd rect
			(at 2.050034 42.0751 270)
			(size 0.519938 1.4986)
			(layers "F.Cu" "F.Mask" "F.Paste")
			(net "M_C_CPU1_SB_DQ<14>")
		)
		(pad "264" smd rect
			(at 2.050034 42.924984 270)
			(size 0.519938 1.4986)
			(layers "F.Cu" "F.Mask" "F.Paste")
			(net "GND")
		)
		(pad "265" smd rect
			(at 2.050034 43.775122 270)
			(size 0.519938 1.4986)
			(layers "F.Cu" "F.Mask" "F.Paste")
			(net "M_C_CPU1_SB_DQ<15>")
		)
		(pad "266" smd rect
			(at 2.050034 44.625006 270)
			(size 0.519938 1.4986)
			(layers "F.Cu" "F.Mask" "F.Paste")
			(net "GND")
		)
		(pad "267" smd rect
			(at 2.050034 45.47489 270)
			(size 0.519938 1.4986)
			(layers "F.Cu" "F.Mask" "F.Paste")
			(net "M_C_CPU1_SB_DQ<18>")
		)
		(pad "268" smd rect
			(at 2.050034 46.325028 270)
			(size 0.519938 1.4986)
			(layers "F.Cu" "F.Mask" "F.Paste")
			(net "GND")
		)
		(pad "269" smd rect
			(at 2.050034 47.174912 270)
			(size 0.519938 1.4986)
			(layers "F.Cu" "F.Mask" "F.Paste")
			(net "M_C_CPU1_SB_DQ<19>")
		)
		(pad "270" smd rect
			(at 2.050034 48.02505 270)
			(size 0.519938 1.4986)
			(layers "F.Cu" "F.Mask" "F.Paste")
			(net "GND")
		)
		(pad "271" smd rect
			(at 2.050034 48.874934 270)
			(size 0.519938 1.4986)
			(layers "F.Cu" "F.Mask" "F.Paste")
			(net "M_C_CPU1_SB_DQS_DN<7>")
		)
		(pad "272" smd rect
			(at 2.050034 49.725072 270)
			(size 0.519938 1.4986)
			(layers "F.Cu" "F.Mask" "F.Paste")
			(net "M_C_CPU1_SB_DQS_DP<7>")
		)
		(pad "273" smd rect
			(at 2.050034 50.574956 270)
			(size 0.519938 1.4986)
			(layers "F.Cu" "F.Mask" "F.Paste")
			(net "GND")
		)
		(pad "274" smd rect
			(at 2.050034 51.425094 270)
			(size 0.519938 1.4986)
			(layers "F.Cu" "F.Mask" "F.Paste")
			(net "M_C_CPU1_SB_DQ<22>")
		)
	)
)
